(kicad_pcb
	(version 20260206)
	(generator "pcbnew")
	(generator_version "10.0")
	(general
		(thickness 1.6)
		(legacy_teardrops no)
	)
	(paper "A4")
	(title_block
		(title "Bryce Canyon_F.DPB_16315-1-OCP.brd")
		(comment 1 "Bryce Canyon / footprints 2048-2053 of 2223")
	)
	(layers
		(0 "F.Cu" signal "TOP")
		(4 "In1.Cu" signal "L2GND")
		(6 "In2.Cu" signal "L3")
		(8 "In3.Cu" signal "L4GND")
		(10 "In4.Cu" signal "L5")
		(12 "In5.Cu" signal "L6VCC")
		(14 "In6.Cu" signal "L7VCC")
		(16 "In7.Cu" signal "L8")
		(18 "In8.Cu" signal "L9GND")
		(20 "In9.Cu" signal "L10")
		(22 "In10.Cu" signal "L11GND")
		(2 "B.Cu" signal "BOTTOM")
		(9 "F.Adhes" user "F.Adhesive")
		(11 "B.Adhes" user "B.Adhesive")
		(13 "F.Paste" user "Package Geometry/Pastemask Top")
		(15 "B.Paste" user "Package Geometry/Pastemask Bottom")
		(5 "F.SilkS" user "Ref Des/Silkscreen Top")
		(7 "B.SilkS" user "Ref Des/Silkscreen Bottom")
		(1 "F.Mask" user "Board Geometry/Soldermask Top")
		(3 "B.Mask" user "Board Geometry/Soldermask Bottom")
		(17 "Dwgs.User" user "User.Drawings")
		(19 "Cmts.User" user "User.Comments")
		(21 "Eco1.User" user "User.Eco1")
		(23 "Eco2.User" user "User.Eco2")
		(25 "Edge.Cuts" user "Board Geometry/Outline")
		(27 "Margin" user)
		(31 "F.CrtYd" user "Package Geometry/Place Bound Top")
		(29 "B.CrtYd" user "Package Geometry/Place Bound Bottom")
		(35 "F.Fab" user "Ref Des/Assembly Top")
		(33 "B.Fab" user "Ref Des/Assembly Bottom")
	)
	(footprint ""
		(layer "B.Cu")
		(at 185.644028 -225.679508 180)
		(property "Reference" "U33"
			(at 0 0 0)
			(layer "B.SilkS")
			(hide yes)
			(effects
				(font
					(size 1.27 1.27)
				)
				(justify mirror)
			)
		)
		(property "Value" "TPS53312RGTR-GP"
			(at -4.9784 -6.9342 180)
			(unlocked yes)
			(layer "B.Fab")
			(hide yes)
			(effects
				(font
					(size 1.016 1.016)
					(thickness 0.1524)
				)
				(justify mirror)
			)
		)
		(property "Device Type" "QFN16G3-G1D7H40"
			(at -4.9784 -8.4582 180)
			(unlocked yes)
			(layer "B.Fab")
			(hide yes)
			(effects
				(font
					(size 1.016 1.016)
					(thickness 0.1524)
				)
				(justify mirror)
			)
		)
		(duplicate_pad_numbers_are_jumpers no)
		(fp_line
			(start 2.5146 2.5146)
			(end 1.2446 2.5146)
			(stroke
				(width 0.1524)
				(type default)
			)
			(layer "B.SilkS")
		)
		(fp_line
			(start 2.5146 1.2446)
			(end 2.5146 2.5146)
			(stroke
				(width 0.1524)
				(type default)
			)
			(layer "B.SilkS")
		)
		(fp_line
			(start 2.5146 -2.5146)
			(end 2.5146 -1.2446)
			(stroke
				(width 0.1524)
				(type default)
			)
			(layer "B.SilkS")
		)
		(fp_line
			(start 2.262124 -0.750062)
			(end 2.770124 -0.750062)
			(stroke
				(width 0.1524)
				(type default)
			)
			(layer "B.SilkS")
		)
		(fp_line
			(start 1.2446 -2.5146)
			(end 2.5146 -2.5146)
			(stroke
				(width 0.1524)
				(type default)
			)
			(layer "B.SilkS")
		)
		(fp_line
			(start 0.249936 2.262124)
			(end 0.249936 3.024124)
			(stroke
				(width 0.1524)
				(type default)
			)
			(layer "B.SilkS")
		)
		(fp_line
			(start -1.2446 2.5146)
			(end -2.5146 2.5146)
			(stroke
				(width 0.1524)
				(type default)
			)
			(layer "B.SilkS")
		)
		(fp_line
			(start -2.262124 -0.249936)
			(end -2.770124 -0.249936)
			(stroke
				(width 0.1524)
				(type default)
			)
			(layer "B.SilkS")
		)
		(fp_line
			(start -2.5146 2.5146)
			(end -2.5146 1.2446)
			(stroke
				(width 0.1524)
				(type default)
			)
			(layer "B.SilkS")
		)
		(fp_poly
			(pts
				(xy -2.5146 -2.5146) (xy -1.2446 -2.5146) (xy -2.5146 -1.2446)
			)
			(stroke
				(width 0)
				(type default)
			)
			(fill yes)
			(layer "B.SilkS")
		)
		(fp_rect
			(start 1.4986 1.4986)
			(end -1.4986 -1.4986)
			(stroke
				(width 0)
				(type default)
			)
			(fill no)
			(layer "B.CrtYd")
		)
		(fp_poly
			(pts
				(xy -2.5146 -1.4986) (xy 1.4986 -1.4986) (xy 1.4986 1.4986) (xy -1.4986 1.4986) (xy -1.4986 -1.4859)
				(xy -2.5146 -1.4859) (xy -2.5146 2.5146) (xy 2.5146 2.5146) (xy 2.5146 -2.5146) (xy -2.5146 -2.5146)
			)
			(stroke
				(width 0)
				(type default)
			)
			(fill no)
			(layer "B.CrtYd")
		)
		(fp_rect
			(start 2.5146 2.5146)
			(end -2.5146 -2.5146)
			(stroke
				(width 0)
				(type default)
			)
			(fill no)
			(layer "B.Fab")
		)
		(pad "1" smd rect
			(at -0.750062 -1.550924)
			(size 0.3048 0.9144)
			(layers "B.Cu" "B.Mask" "B.Paste")
			(net "P3V3_STBY_VFB")
		)
		(pad "2" smd rect
			(at -0.249936 -1.538224)
			(size 0.3048 0.9398)
			(layers "B.Cu" "B.Mask" "B.Paste")
			(net "P3V3_STBY_VRG5")
		)
		(pad "3" smd rect
			(at 0.249936 -1.538224)
			(size 0.3048 0.9398)
			(layers "B.Cu" "B.Mask" "B.Paste")
			(net "P3V3_STBY_SS")
		)
		(pad "4" smd rect
			(at 0.750062 -1.550924)
			(size 0.3048 0.9144)
			(layers "B.Cu" "B.Mask" "B.Paste")
			(net "AGND_P3V3_STBY")
		)
		(pad "5" smd rect
			(at 1.550924 -0.750062)
			(size 0.9144 0.3048)
			(layers "B.Cu" "B.Mask" "B.Paste")
			(net "PWRGD_P3V3_STBY")
		)
		(pad "6" smd rect
			(at 1.538224 -0.249936)
			(size 0.9398 0.3048)
			(layers "B.Cu" "B.Mask" "B.Paste")
			(net "P3V3_STBY_EN_R")
		)
		(pad "7" smd rect
			(at 1.538224 0.249936)
			(size 0.9398 0.3048)
			(layers "B.Cu" "B.Mask" "B.Paste")
			(net "GND")
		)
		(pad "8" smd rect
			(at 1.550924 0.750062)
			(size 0.9144 0.3048)
			(layers "B.Cu" "B.Mask" "B.Paste")
			(net "GND")
		)
		(pad "9" smd rect
			(at 0.750062 1.550924)
			(size 0.3048 0.9144)
			(layers "B.Cu" "B.Mask" "B.Paste")
			(net "P3V3_STBY_SW")
		)
		(pad "10" smd rect
			(at 0.249936 1.538224)
			(size 0.3048 0.9398)
			(layers "B.Cu" "B.Mask" "B.Paste")
			(net "P3V3_STBY_SW")
		)
		(pad "11" smd rect
			(at -0.249936 1.538224)
			(size 0.3048 0.9398)
			(layers "B.Cu" "B.Mask" "B.Paste")
			(net "P3V3_STBY_SW")
		)
		(pad "12" smd rect
			(at -0.750062 1.550924)
			(size 0.3048 0.9144)
			(layers "B.Cu" "B.Mask" "B.Paste")
			(net "P3V3_STBY_VBST")
		)
		(pad "13" smd rect
			(at -1.550924 0.750062)
			(size 0.9144 0.3048)
			(layers "B.Cu" "B.Mask" "B.Paste")
			(net "P3V3_STBY_VIN")
		)
		(pad "14" smd rect
			(at -1.538224 0.249936)
			(size 0.9398 0.3048)
			(layers "B.Cu" "B.Mask" "B.Paste")
			(net "P3V3_STBY_VIN")
		)
		(pad "15" smd rect
			(at -1.538224 -0.249936)
			(size 0.9398 0.3048)
			(layers "B.Cu" "B.Mask" "B.Paste")
			(net "P3V3_STBY_VCC")
		)
		(pad "16" smd rect
			(at -1.550924 -0.750062)
			(size 0.9144 0.3048)
			(layers "B.Cu" "B.Mask" "B.Paste")
			(net "P3V3_STBY_VO")
		)
		(pad "17" smd rect
			(at 0 0)
			(size 1.6764 1.6764)
			(layers "B.Cu" "B.Mask" "B.Paste")
			(net "GND")
		)
	)
	(footprint ""
		(layer "B.Cu")
		(at 246.253 -386.2578 -90)
		(property "Reference" "R1156"
			(at 0 0 90)
			(layer "B.SilkS")
			(hide yes)
			(effects
				(font
					(size 1.27 1.27)
				)
				(justify mirror)
			)
		)
		(property "Value" "10R2F-L-GP"
			(at -0.064008 -3.993896 270)
			(unlocked yes)
			(layer "B.Fab")
			(hide yes)
			(effects
				(font
					(size 1.016 1.016)
					(thickness 0.1524)
				)
				(justify mirror)
			)
		)
		(property "Device Type" "R402H14"
			(at -0.064008 -5.517896 270)
			(unlocked yes)
			(layer "B.Fab")
			(hide yes)
			(effects
				(font
					(size 1.016 1.016)
					(thickness 0.1524)
				)
				(justify mirror)
			)
		)
		(duplicate_pad_numbers_are_jumpers no)
		(fp_line
			(start -0.508 -0.9398)
			(end 0.508 -0.9398)
			(stroke
				(width 0.1524)
				(type default)
			)
			(layer "B.SilkS")
		)
		(fp_line
			(start 0.508 -0.9398)
			(end 0.508 0.9398)
			(stroke
				(width 0.1524)
				(type default)
			)
			(layer "B.SilkS")
		)
		(fp_rect
			(start 0.508 0.9398)
			(end -0.508 -0.9398)
			(stroke
				(width 0)
				(type default)
			)
			(fill no)
			(layer "B.CrtYd")
		)
		(fp_rect
			(start 0.508 0.9398)
			(end -0.508 -0.9398)
			(stroke
				(width 0)
				(type default)
			)
			(fill no)
			(layer "B.Fab")
		)
		(pad "1" smd custom
			(at 0 -0.4445 90)
			(size 0.1397 0.1397)
			(layers "B.Cu" "B.Mask" "B.Paste")
			(net "MB3_CM_SENSE_R1_N")
			(options
				(clearance outline)
				(anchor circle)
			)
			(primitives
				(gr_poly
					(pts
						(arc
							(start -0.1778 0.2794)
							(mid -0.249642 0.249642)
							(end -0.2794 0.1778)
						)
						(arc
							(start -0.2794 -0.1778)
							(mid -0.249642 -0.249642)
							(end -0.1778 -0.2794)
						)
						(arc
							(start 0.1778 -0.2794)
							(mid 0.249642 -0.249642)
							(end 0.2794 -0.1778)
						)
						(arc
							(start 0.2794 0.1778)
							(mid 0.249642 0.249642)
							(end 0.1778 0.2794)
						)
					)
					(width 0)
					(fill yes)
				)
			)
		)
		(pad "2" smd custom
			(at 0 0.4445 90)
			(size 0.1397 0.1397)
			(layers "B.Cu" "B.Mask" "B.Paste")
			(net "MB3_CM_SENSE_N")
			(options
				(clearance outline)
				(anchor circle)
			)
			(primitives
				(gr_poly
					(pts
						(arc
							(start -0.1778 0.2794)
							(mid -0.249642 0.249642)
							(end -0.2794 0.1778)
						)
						(arc
							(start -0.2794 -0.1778)
							(mid -0.249642 -0.249642)
							(end -0.1778 -0.2794)
						)
						(arc
							(start 0.1778 -0.2794)
							(mid 0.249642 -0.249642)
							(end 0.2794 -0.1778)
						)
						(arc
							(start 0.2794 0.1778)
							(mid 0.249642 0.249642)
							(end 0.1778 0.2794)
						)
					)
					(width 0)
					(fill yes)
				)
			)
		)
	)
	(footprint ""
		(layer "B.Cu")
		(at 469.646 -229.616 90)
		(property "Reference" "C656"
			(at 0 0 90)
			(layer "B.SilkS")
			(hide yes)
			(effects
				(font
					(size 1.27 1.27)
				)
				(justify mirror)
			)
		)
		(property "Value" "SCD1U16V2KX-3GP"
			(at -1.1811 -2.7051 90)
			(unlocked yes)
			(layer "B.Fab")
			(hide yes)
			(effects
				(font
					(size 1.016 1.016)
					(thickness 0.1524)
				)
				(justify mirror)
			)
		)
		(property "Device Type" "C402H22"
			(at -1.1811 -4.2291 90)
			(unlocked yes)
			(layer "B.Fab")
			(hide yes)
			(effects
				(font
					(size 1.016 1.016)
					(thickness 0.1524)
				)
				(justify mirror)
			)
		)
		(duplicate_pad_numbers_are_jumpers no)
		(fp_rect
			(start 0.4318 0.9525)
			(end -0.4318 -0.9525)
			(stroke
				(width 0)
				(type default)
			)
			(fill no)
			(layer "B.CrtYd")
		)
		(fp_rect
			(start 0.4318 0.9525)
			(end -0.4318 -0.9525)
			(stroke
				(width 0)
				(type default)
			)
			(fill no)
			(layer "B.Fab")
		)
		(pad "1" smd custom
			(at 0 -0.4445 270)
			(size 0.1524 0.1524)
			(layers "B.Cu" "B.Mask" "B.Paste")
			(net "P5V_D_VBST_RC")
			(options
				(clearance outline)
				(anchor circle)
			)
			(primitives
				(gr_poly
					(pts
						(arc
							(start 0.3048 0.2032)
							(mid 0.275042 0.275042)
							(end 0.2032 0.3048)
						)
						(arc
							(start -0.2032 0.3048)
							(mid -0.275042 0.275042)
							(end -0.3048 0.2032)
						)
						(arc
							(start -0.3048 -0.2032)
							(mid -0.275042 -0.275042)
							(end -0.2032 -0.3048)
						)
						(arc
							(start 0.2032 -0.3048)
							(mid 0.275042 -0.275042)
							(end 0.3048 -0.2032)
						)
					)
					(width 0)
					(fill yes)
				)
			)
		)
		(pad "2" smd custom
			(at 0 0.4445 270)
			(size 0.1524 0.1524)
			(layers "B.Cu" "B.Mask" "B.Paste")
			(net "P5V_D_LL")
			(options
				(clearance outline)
				(anchor circle)
			)
			(primitives
				(gr_poly
					(pts
						(arc
							(start 0.3048 0.2032)
							(mid 0.275042 0.275042)
							(end 0.2032 0.3048)
						)
						(arc
							(start -0.2032 0.3048)
							(mid -0.275042 0.275042)
							(end -0.3048 0.2032)
						)
						(arc
							(start -0.3048 -0.2032)
							(mid -0.275042 -0.275042)
							(end -0.2032 -0.3048)
						)
						(arc
							(start 0.2032 -0.3048)
							(mid 0.275042 -0.275042)
							(end 0.3048 -0.2032)
						)
					)
					(width 0)
					(fill yes)
				)
			)
		)
	)
	(footprint ""
		(layer "B.Cu")
		(at 479.139504 -233.136186 -90)
		(property "Reference" "PG17"
			(at 0 0 90)
			(layer "B.SilkS")
			(hide yes)
			(effects
				(font
					(size 1.27 1.27)
				)
				(justify mirror)
			)
		)
		(property "Value" "COPPER-CLOSE-GP-U"
			(at -0.0762 -2.8702 270)
			(unlocked yes)
			(layer "B.Fab")
			(hide yes)
			(effects
				(font
					(size 1.016 1.016)
					(thickness 0.1524)
				)
				(justify mirror)
			)
		)
		(property "Device Type" "CON2C-U"
			(at -0.0762 -4.3942 270)
			(unlocked yes)
			(layer "B.Fab")
			(hide yes)
			(effects
				(font
					(size 1.016 1.016)
					(thickness 0.1524)
				)
				(justify mirror)
			)
		)
		(duplicate_pad_numbers_are_jumpers no)
		(fp_rect
			(start 0.9398 0.9652)
			(end -0.9398 -0.9652)
			(stroke
				(width 0)
				(type default)
			)
			(fill no)
			(layer "B.CrtYd")
		)
		(fp_rect
			(start 0.9398 0.9652)
			(end -0.9398 -0.9652)
			(stroke
				(width 0)
				(type default)
			)
			(fill no)
			(layer "B.Fab")
		)
		(pad "1" smd custom
			(at 0 -0.5334 90)
			(size 0.17145 0.17145)
			(layers "B.Cu" "B.Mask" "B.Paste")
			(net "AGND_P5V_D")
			(options
				(clearance outline)
				(anchor circle)
			)
			(primitives
				(gr_poly
					(pts
						(xy -0.127 -0.3429) (xy -0.127 -0.1651) (xy -0.635 0.3429) (xy 0.635 0.3429) (xy 0.127 -0.1651)
						(xy 0.127 -0.3429)
					)
					(width 0)
					(fill yes)
				)
			)
		)
		(pad "2" smd custom
			(at 0 0.5334 90)
			(size 0.17145 0.17145)
			(layers "B.Cu" "B.Mask" "B.Paste")
			(net "GND")
			(options
				(clearance outline)
				(anchor circle)
			)
			(primitives
				(gr_poly
					(pts
						(xy -0.635 -0.3429) (xy -0.127 0.1651) (xy -0.127 0.3429) (xy 0.127 0.3429) (xy 0.127 0.1651)
						(xy 0.635 -0.3429)
					)
					(width 0)
					(fill yes)
				)
			)
		)
	)
	(footprint ""
		(layer "B.Cu")
		(at 218.7702 -116.4844 -90)
		(property "Reference" "R619"
			(at 0 0 90)
			(layer "B.SilkS")
			(hide yes)
			(effects
				(font
					(size 1.27 1.27)
				)
				(justify mirror)
			)
		)
		(property "Value" "4K7R2F-GP"
			(at -0.064008 -3.993896 270)
			(unlocked yes)
			(layer "B.Fab")
			(hide yes)
			(effects
				(font
					(size 1.016 1.016)
					(thickness 0.1524)
				)
				(justify mirror)
			)
		)
		(property "Device Type" "R402H16"
			(at -0.064008 -5.517896 270)
			(unlocked yes)
			(layer "B.Fab")
			(hide yes)
			(effects
				(font
					(size 1.016 1.016)
					(thickness 0.1524)
				)
				(justify mirror)
			)
		)
		(duplicate_pad_numbers_are_jumpers no)
		(fp_line
			(start -0.508 -0.9398)
			(end 0.508 -0.9398)
			(stroke
				(width 0.1524)
				(type default)
			)
			(layer "B.SilkS")
		)
		(fp_line
			(start 0.508 -0.9398)
			(end 0.508 0.9398)
			(stroke
				(width 0.1524)
				(type default)
			)
			(layer "B.SilkS")
		)
		(fp_rect
			(start 0.508 0.9398)
			(end -0.508 -0.9398)
			(stroke
				(width 0)
				(type default)
			)
			(fill no)
			(layer "B.CrtYd")
		)
		(fp_rect
			(start 0.508 0.9398)
			(end -0.508 -0.9398)
			(stroke
				(width 0)
				(type default)
			)
			(fill no)
			(layer "B.Fab")
		)
		(pad "1" smd custom
			(at 0 -0.4445 90)
			(size 0.1397 0.1397)
			(layers "B.Cu" "B.Mask" "B.Paste")
			(net "I2C_BMC_A_COMP_A_SCL")
			(options
				(clearance outline)
				(anchor circle)
			)
			(primitives
				(gr_poly
					(pts
						(arc
							(start -0.1778 0.2794)
							(mid -0.249642 0.249642)
							(end -0.2794 0.1778)
						)
						(arc
							(start -0.2794 -0.1778)
							(mid -0.249642 -0.249642)
							(end -0.1778 -0.2794)
						)
						(arc
							(start 0.1778 -0.2794)
							(mid 0.249642 -0.249642)
							(end 0.2794 -0.1778)
						)
						(arc
							(start 0.2794 0.1778)
							(mid 0.249642 0.249642)
							(end 0.1778 0.2794)
						)
					)
					(width 0)
					(fill yes)
				)
			)
		)
		(pad "2" smd custom
			(at 0 0.4445 90)
			(size 0.1397 0.1397)
			(layers "B.Cu" "B.Mask" "B.Paste")
			(net "P3V3_STBY_A")
			(options
				(clearance outline)
				(anchor circle)
			)
			(primitives
				(gr_poly
					(pts
						(arc
							(start -0.1778 0.2794)
							(mid -0.249642 0.249642)
							(end -0.2794 0.1778)
						)
						(arc
							(start -0.2794 -0.1778)
							(mid -0.249642 -0.249642)
							(end -0.1778 -0.2794)
						)
						(arc
							(start 0.1778 -0.2794)
							(mid 0.249642 -0.249642)
							(end 0.2794 -0.1778)
						)
						(arc
							(start 0.2794 0.1778)
							(mid 0.249642 0.249642)
							(end 0.1778 0.2794)
						)
					)
					(width 0)
					(fill yes)
				)
			)
		)
	)
	(footprint ""
		(layer "B.Cu")
		(at 57.674002 -252.02515 -90)
		(property "Reference" "PG10"
			(at 0 0 90)
			(layer "B.SilkS")
			(hide yes)
			(effects
				(font
					(size 1.27 1.27)
				)
				(justify mirror)
			)
		)
		(property "Value" "GAP-CLOSE-PWR-4-GP"
			(at 2.4638 -0.5461 270)
			(unlocked yes)
			(layer "B.Fab")
			(hide yes)
			(effects
				(font
					(size 1.016 1.016)
					(thickness 0.1524)
				)
				(justify mirror)
			)
		)
		(property "Device Type" "GAP-CLOSE-PWR-4"
			(at 2.4638 -2.0701 270)
			(unlocked yes)
			(layer "B.Fab")
			(hide yes)
			(effects
				(font
					(size 1.016 1.016)
					(thickness 0.1524)
				)
				(justify mirror)
			)
		)
		(duplicate_pad_numbers_are_jumpers no)
		(fp_rect
			(start 0.2794 0.254)
			(end -0.2794 -0.254)
			(stroke
				(width 0)
				(type default)
			)
			(fill no)
			(layer "B.CrtYd")
		)
		(fp_rect
			(start 0.2794 0.254)
			(end -0.2794 -0.254)
			(stroke
				(width 0)
				(type default)
			)
			(fill no)
			(layer "B.Fab")
		)
		(pad "1" smd rect
			(at 0.0635 0 90)
			(size 0.1778 0.254)
			(layers "B.Cu" "B.Mask" "B.Paste")
			(net "P5V_A_1")
		)
		(pad "2" smd rect
			(at -0.0635 0 90)
			(size 0.1778 0.254)
			(layers "B.Cu" "B.Mask" "B.Paste")
			(net "P5V_A_CC")
		)
	)
)
